# T6G (Grand Teton) — schematic netlist excerpt (pin names and nets, part order shuffled) for the footprints in the layout excerpt that follows; sources: Cadence DE-HDL packaged netlist, KiCad conversion of 04192023_DAF0TMB3IC0_F0TG_MB_C_brd_V02_OCP.brd

R6096  Q_RES  0 5% CHIP  pkg 0402LF  page 80 : A = FM_UV_ADR_TRIGGER_R_N ; B = FM_UV_ADR_TRIGGER_N
R6702  Q_RES  0 5% EMPTY  pkg 0402LF  page 323 : A = P1V8_CPU1_RT0_1A_1D ; B = P1V8_CPU1_RT0_1A

(kicad_pcb
	(version 20260206)
	(generator "pcbnew")
	(generator_version "10.0")
	(general
		(thickness 1.6)
		(legacy_teardrops no)
	)
	(paper "A4")
	(title_block
		(title "04192023_DAF0TMB3IC0_F0TG_MB_C_brd_V02_OCP.brd")
		(comment 1 "Grand Teton / footprints 4165-4166 of 8354")
	)
	(layers
		(0 "F.Cu" signal "TOP")
		(4 "In1.Cu" signal "GND")
		(6 "In2.Cu" signal "IN1")
		(8 "In3.Cu" signal "GND1")
		(10 "In4.Cu" signal "IN2")
		(12 "In5.Cu" signal "GND2")
		(14 "In6.Cu" signal "IN3")
		(16 "In7.Cu" signal "GND3")
		(18 "In8.Cu" signal "VCC")
		(20 "In9.Cu" signal "VCC1")
		(22 "In10.Cu" signal "GND4")
		(24 "In11.Cu" signal "IN4")
		(26 "In12.Cu" signal "GND5")
		(28 "In13.Cu" signal "IN5")
		(30 "In14.Cu" signal "GND6")
		(32 "In15.Cu" signal "IN6")
		(34 "In16.Cu" signal "GND7")
		(2 "B.Cu" signal "BOTTOM")
		(9 "F.Adhes" user "F.Adhesive")
		(11 "B.Adhes" user "B.Adhesive")
		(13 "F.Paste" user "Package Geometry/Pastemask Top")
		(15 "B.Paste" user "Package Geometry/Pastemask Bottom")
		(5 "F.SilkS" user "Ref Des/Silkscreen Top")
		(7 "B.SilkS" user "Ref Des/Silkscreen Bottom")
		(1 "F.Mask" user "Board Geometry/Soldermask Top")
		(3 "B.Mask" user "Board Geometry/Soldermask Bottom")
		(17 "Dwgs.User" user "User.Drawings")
		(19 "Cmts.User" user "User.Comments")
		(21 "Eco1.User" user "User.Eco1")
		(23 "Eco2.User" user "User.Eco2")
		(25 "Edge.Cuts" user "Board Geometry/Outline")
		(27 "Margin" user)
		(31 "F.CrtYd" user "Package Geometry/Place Bound Top")
		(29 "B.CrtYd" user "Package Geometry/Place Bound Bottom")
		(35 "F.Fab" user "Ref Des/Assembly Top")
		(33 "B.Fab" user "Ref Des/Assembly Bottom")
	)
	(footprint ""
		(layer "F.Cu")
		(at 167.132 -109.184948 180)
		(property "Reference" "R6096"
			(at 0 0 180)
			(layer "F.SilkS")
			(hide yes)
			(effects
				(font
					(size 1.27 1.27)
				)
			)
		)
		(property "Value" ""
			(at 0 0 180)
			(layer "F.Fab")
			(effects
				(font
					(size 1.27 1.27)
				)
			)
		)
		(duplicate_pad_numbers_are_jumpers no)
		(fp_line
			(start 0.7874 0.4064)
			(end -0.7874 0.4064)
			(stroke
				(width 0.1524)
				(type default)
			)
			(layer "F.SilkS")
		)
		(fp_line
			(start 0.7874 -0.4064)
			(end 0.7874 0.4064)
			(stroke
				(width 0.1524)
				(type default)
			)
			(layer "F.SilkS")
		)
		(fp_line
			(start -0.7874 0.4064)
			(end -0.7874 -0.4064)
			(stroke
				(width 0.1524)
				(type default)
			)
			(layer "F.SilkS")
		)
		(fp_line
			(start -0.7874 -0.4064)
			(end 0.7874 -0.4064)
			(stroke
				(width 0.1524)
				(type default)
			)
			(layer "F.SilkS")
		)
		(fp_line
			(start 0.67945 0.3048)
			(end 0.120396 0.3048)
			(stroke
				(width 0.1)
				(type default)
			)
			(layer "F.Fab")
		)
		(fp_line
			(start 0.67945 -0.3048)
			(end 0.67945 0.3048)
			(stroke
				(width 0.1)
				(type default)
			)
			(layer "F.Fab")
		)
		(fp_line
			(start 0.12065 -0.2794)
			(end 0.12065 -0.3048)
			(stroke
				(width 0.1)
				(type default)
			)
			(layer "F.Fab")
		)
		(fp_line
			(start 0.12065 -0.3048)
			(end 0.67945 -0.3048)
			(stroke
				(width 0.1)
				(type default)
			)
			(layer "F.Fab")
		)
		(fp_line
			(start 0.120396 0.3048)
			(end 0.120396 0.2794)
			(stroke
				(width 0.1)
				(type default)
			)
			(layer "F.Fab")
		)
		(fp_line
			(start 0.120396 0.2794)
			(end -0.12065 0.2794)
			(stroke
				(width 0.1)
				(type default)
			)
			(layer "F.Fab")
		)
		(fp_line
			(start -0.12065 0.3048)
			(end -0.67945 0.3048)
			(stroke
				(width 0.1)
				(type default)
			)
			(layer "F.Fab")
		)
		(fp_line
			(start -0.12065 0.2794)
			(end -0.12065 0.3048)
			(stroke
				(width 0.1)
				(type default)
			)
			(layer "F.Fab")
		)
		(fp_line
			(start -0.12065 -0.2794)
			(end 0.12065 -0.2794)
			(stroke
				(width 0.1)
				(type default)
			)
			(layer "F.Fab")
		)
		(fp_line
			(start -0.12065 -0.305054)
			(end -0.12065 -0.2794)
			(stroke
				(width 0.1)
				(type default)
			)
			(layer "F.Fab")
		)
		(fp_line
			(start -0.67945 0.3048)
			(end -0.67945 -0.305054)
			(stroke
				(width 0.1)
				(type default)
			)
			(layer "F.Fab")
		)
		(fp_line
			(start -0.67945 -0.305054)
			(end -0.12065 -0.305054)
			(stroke
				(width 0.1)
				(type default)
			)
			(layer "F.Fab")
		)
		(pad "1" smd circle
			(at -0.40005 0 180)
			(size 0 0)
			(layers "F.Cu" "F.Mask" "F.Paste")
			(net "FM_UV_ADR_TRIGGER_R_N")
		)
		(pad "2" smd circle
			(at 0.40005 0 180)
			(size 0 0)
			(layers "F.Cu" "F.Mask" "F.Paste")
			(net "FM_UV_ADR_TRIGGER_N")
		)
	)
	(footprint ""
		(layer "F.Cu")
		(at 69.862446 -385.09448 180)
		(property "Reference" "R6702"
			(at 0 0 180)
			(layer "F.SilkS")
			(hide yes)
			(effects
				(font
					(size 1.27 1.27)
				)
			)
		)
		(property "Value" ""
			(at 0 0 180)
			(layer "F.Fab")
			(effects
				(font
					(size 1.27 1.27)
				)
			)
		)
		(duplicate_pad_numbers_are_jumpers no)
		(fp_line
			(start 0.7874 0.4064)
			(end -0.7874 0.4064)
			(stroke
				(width 0.1524)
				(type default)
			)
			(layer "F.SilkS")
		)
		(fp_line
			(start 0.7874 -0.4064)
			(end 0.7874 0.4064)
			(stroke
				(width 0.1524)
				(type default)
			)
			(layer "F.SilkS")
		)
		(fp_line
			(start -0.7874 0.4064)
			(end -0.7874 -0.4064)
			(stroke
				(width 0.1524)
				(type default)
			)
			(layer "F.SilkS")
		)
		(fp_line
			(start -0.7874 -0.4064)
			(end 0.7874 -0.4064)
			(stroke
				(width 0.1524)
				(type default)
			)
			(layer "F.SilkS")
		)
		(fp_line
			(start 0.67945 0.3048)
			(end 0.120396 0.3048)
			(stroke
				(width 0.1)
				(type default)
			)
			(layer "F.Fab")
		)
		(fp_line
			(start 0.67945 -0.3048)
			(end 0.67945 0.3048)
			(stroke
				(width 0.1)
				(type default)
			)
			(layer "F.Fab")
		)
		(fp_line
			(start 0.12065 -0.2794)
			(end 0.12065 -0.3048)
			(stroke
				(width 0.1)
				(type default)
			)
			(layer "F.Fab")
		)
		(fp_line
			(start 0.12065 -0.3048)
			(end 0.67945 -0.3048)
			(stroke
				(width 0.1)
				(type default)
			)
			(layer "F.Fab")
		)
		(fp_line
			(start 0.120396 0.3048)
			(end 0.120396 0.2794)
			(stroke
				(width 0.1)
				(type default)
			)
			(layer "F.Fab")
		)
		(fp_line
			(start 0.120396 0.2794)
			(end -0.12065 0.2794)
			(stroke
				(width 0.1)
				(type default)
			)
			(layer "F.Fab")
		)
		(fp_line
			(start -0.12065 0.3048)
			(end -0.67945 0.3048)
			(stroke
				(width 0.1)
				(type default)
			)
			(layer "F.Fab")
		)
		(fp_line
			(start -0.12065 0.2794)
			(end -0.12065 0.3048)
			(stroke
				(width 0.1)
				(type default)
			)
			(layer "F.Fab")
		)
		(fp_line
			(start -0.12065 -0.2794)
			(end 0.12065 -0.2794)
			(stroke
				(width 0.1)
				(type default)
			)
			(layer "F.Fab")
		)
		(fp_line
			(start -0.12065 -0.305054)
			(end -0.12065 -0.2794)
			(stroke
				(width 0.1)
				(type default)
			)
			(layer "F.Fab")
		)
		(fp_line
			(start -0.67945 0.3048)
			(end -0.67945 -0.305054)
			(stroke
				(width 0.1)
				(type default)
			)
			(layer "F.Fab")
		)
		(fp_line
			(start -0.67945 -0.305054)
			(end -0.12065 -0.305054)
			(stroke
				(width 0.1)
				(type default)
			)
			(layer "F.Fab")
		)
		(pad "1" smd rect
			(at -0.40005 0)
			(size 0.4572 0.508)
			(layers "F.Cu" "F.Mask" "F.Paste")
			(net "P1V8_CPU1_RT0_1A_1D")
		)
		(pad "2" smd rect
			(at 0.40005 0)
			(size 0.4572 0.508)
			(layers "F.Cu" "F.Mask" "F.Paste")
			(net "P1V8_CPU1_RT0_1A")
		)
	)
)
